(kicad_pcb
	(version 20260206)
	(generator "pcbnew")
	(generator_version "10.0")
	(general
		(thickness 1.6)
		(legacy_teardrops no)
	)
	(paper "A4")
	(title_block
		(title "Wiwynn_Tioga_Pass_MB.brd")
		(comment 1 "Tioga Pass / footprints 748-751 of 4770")
	)
	(layers
		(0 "F.Cu" signal "TOP")
		(4 "In1.Cu" signal "L2GND")
		(6 "In2.Cu" signal "L3")
		(8 "In3.Cu" signal "L4GND")
		(10 "In4.Cu" signal "L5")
		(12 "In5.Cu" signal "L6GND")
		(14 "In6.Cu" signal "L7VCC")
		(16 "In7.Cu" signal "L8VCC")
		(18 "In8.Cu" signal "L9GND")
		(20 "In9.Cu" signal "L10")
		(22 "In10.Cu" signal "L11GND")
		(24 "In11.Cu" signal "L12")
		(26 "In12.Cu" signal "L13GND")
		(2 "B.Cu" signal "BOTTOM")
		(9 "F.Adhes" user "F.Adhesive")
		(11 "B.Adhes" user "B.Adhesive")
		(13 "F.Paste" user "Package Geometry/Pastemask Top")
		(15 "B.Paste" user "Package Geometry/Pastemask Bottom")
		(5 "F.SilkS" user "Ref Des/Silkscreen Top")
		(7 "B.SilkS" user "Ref Des/Silkscreen Bottom")
		(1 "F.Mask" user "Board Geometry/Soldermask Top")
		(3 "B.Mask" user "Board Geometry/Soldermask Bottom")
		(17 "Dwgs.User" user "User.Drawings")
		(19 "Cmts.User" user "User.Comments")
		(21 "Eco1.User" user "User.Eco1")
		(23 "Eco2.User" user "User.Eco2")
		(25 "Edge.Cuts" user "Board Geometry/Outline")
		(27 "Margin" user)
		(31 "F.CrtYd" user "Package Geometry/Place Bound Top")
		(29 "B.CrtYd" user "Package Geometry/Place Bound Bottom")
		(35 "F.Fab" user "Ref Des/Assembly Top")
		(33 "B.Fab" user "Ref Des/Assembly Bottom")
	)
	(footprint ""
		(layer "F.Cu")
		(at 179.07 -84.328 180)
		(property "Reference" "R4D70"
			(at 0 0 180)
			(layer "F.SilkS")
			(hide yes)
			(effects
				(font
					(size 1.27 1.27)
				)
			)
		)
		(property "Value" ""
			(at 0 0 180)
			(layer "F.Fab")
			(effects
				(font
					(size 1.27 1.27)
				)
			)
		)
		(duplicate_pad_numbers_are_jumpers no)
		(fp_poly
			(pts
				(xy -0.2794 -0.1016) (xy 0.2794 -0.1016) (xy 0.2794 0.9906) (xy -0.2794 0.9906)
			)
			(stroke
				(width 0)
				(type default)
			)
			(fill no)
			(layer "F.CrtYd")
		)
		(fp_line
			(start 0.2794 0.9906)
			(end 0.2794 -0.1016)
			(stroke
				(width 0.1)
				(type default)
			)
			(layer "F.Fab")
		)
		(fp_line
			(start 0.2794 -0.1016)
			(end -0.2794 -0.1016)
			(stroke
				(width 0.1)
				(type default)
			)
			(layer "F.Fab")
		)
		(fp_line
			(start -0.2794 0.9906)
			(end 0.2794 0.9906)
			(stroke
				(width 0.1)
				(type default)
			)
			(layer "F.Fab")
		)
		(fp_line
			(start -0.2794 -0.1016)
			(end -0.2794 0.9906)
			(stroke
				(width 0.1)
				(type default)
			)
			(layer "F.Fab")
		)
		(pad "1" smd rect
			(at 0 0 180)
			(size 0.508 0.508)
			(layers "F.Cu" "F.Mask" "F.Paste")
			(net "P3V3")
		)
		(pad "2" smd rect
			(at 0 0.889 180)
			(size 0.508 0.508)
			(layers "F.Cu" "F.Mask" "F.Paste")
			(net "FM_CPU0_MCP_CLK_EN_N")
		)
		(zone
			(layer "F.Cu")
			(hatch none 0.5)
			(connect_pads
				(clearance 0)
			)
			(min_thickness 0.25)
			(keepout
				(tracks not_allowed)
				(vias allowed)
				(pads allowed)
				(copperpour not_allowed)
				(footprints allowed)
			)
			(placement
				(enabled no)
				(sheetname "")
			)
			(fill
				(thermal_gap 0.5)
				(thermal_bridge_width 0.5)
				(island_removal_mode 0)
			)
			(polygon
				(pts
					(xy 179.324 -84.963) (xy 178.816 -84.963) (xy 178.816 -84.582) (xy 179.324 -84.582)
				)
			)
		)
		(zone
			(layer "F.Cu")
			(hatch none 0.5)
			(connect_pads
				(clearance 0)
			)
			(min_thickness 0.25)
			(keepout
				(tracks allowed)
				(vias not_allowed)
				(pads allowed)
				(copperpour not_allowed)
				(footprints allowed)
			)
			(placement
				(enabled no)
				(sheetname "")
			)
			(fill
				(thermal_gap 0.5)
				(thermal_bridge_width 0.5)
				(island_removal_mode 0)
			)
			(polygon
				(pts
					(xy 179.324 -84.582) (xy 178.816 -84.582) (xy 178.816 -84.963) (xy 179.324 -84.963)
				)
			)
		)
	)
	(footprint ""
		(layer "F.Cu")
		(at 438.4675 -15.367 90)
		(property "Reference" "R1U53"
			(at 0 0 90)
			(layer "F.SilkS")
			(hide yes)
			(effects
				(font
					(size 1.27 1.27)
				)
			)
		)
		(property "Value" ""
			(at 0 0 90)
			(layer "F.Fab")
			(effects
				(font
					(size 1.27 1.27)
				)
			)
		)
		(duplicate_pad_numbers_are_jumpers no)
		(fp_poly
			(pts
				(xy -0.2794 -0.1016) (xy 0.2794 -0.1016) (xy 0.2794 0.9906) (xy -0.2794 0.9906)
			)
			(stroke
				(width 0)
				(type default)
			)
			(fill no)
			(layer "F.CrtYd")
		)
		(fp_line
			(start 0.2794 -0.1016)
			(end -0.2794 -0.1016)
			(stroke
				(width 0.1)
				(type default)
			)
			(layer "F.Fab")
		)
		(fp_line
			(start -0.2794 -0.1016)
			(end -0.2794 0.9906)
			(stroke
				(width 0.1)
				(type default)
			)
			(layer "F.Fab")
		)
		(fp_line
			(start 0.2794 0.9906)
			(end 0.2794 -0.1016)
			(stroke
				(width 0.1)
				(type default)
			)
			(layer "F.Fab")
		)
		(fp_line
			(start -0.2794 0.9906)
			(end 0.2794 0.9906)
			(stroke
				(width 0.1)
				(type default)
			)
			(layer "F.Fab")
		)
		(pad "1" smd rect
			(at 0 0 90)
			(size 0.508 0.508)
			(layers "F.Cu" "F.Mask" "F.Paste")
			(net "H_CPU1_MEMGHJ_MEMHOT_G_N")
		)
		(pad "2" smd rect
			(at 0 0.889 90)
			(size 0.508 0.508)
			(layers "F.Cu" "F.Mask" "F.Paste")
			(net "H_CPU1_MEMGHJ_MEMHOT_G_R_N")
		)
		(zone
			(layer "F.Cu")
			(hatch none 0.5)
			(connect_pads
				(clearance 0)
			)
			(min_thickness 0.25)
			(keepout
				(tracks allowed)
				(vias not_allowed)
				(pads allowed)
				(copperpour not_allowed)
				(footprints allowed)
			)
			(placement
				(enabled no)
				(sheetname "")
			)
			(fill
				(thermal_gap 0.5)
				(thermal_bridge_width 0.5)
				(island_removal_mode 0)
			)
			(polygon
				(pts
					(xy 438.7215 -15.113) (xy 438.7215 -15.621) (xy 439.1025 -15.621) (xy 439.1025 -15.113)
				)
			)
		)
		(zone
			(layer "F.Cu")
			(hatch none 0.5)
			(connect_pads
				(clearance 0)
			)
			(min_thickness 0.25)
			(keepout
				(tracks not_allowed)
				(vias allowed)
				(pads allowed)
				(copperpour not_allowed)
				(footprints allowed)
			)
			(placement
				(enabled no)
				(sheetname "")
			)
			(fill
				(thermal_gap 0.5)
				(thermal_bridge_width 0.5)
				(island_removal_mode 0)
			)
			(polygon
				(pts
					(xy 439.1025 -15.113) (xy 439.1025 -15.621) (xy 438.7215 -15.621) (xy 438.7215 -15.113)
				)
			)
		)
	)
	(footprint ""
		(layer "F.Cu")
		(at 497.120926 -20.703286 90)
		(property "Reference" "C7E9"
			(at 0 0 90)
			(layer "F.SilkS")
			(hide yes)
			(effects
				(font
					(size 1.27 1.27)
				)
			)
		)
		(property "Value" ""
			(at 0 0 90)
			(layer "F.Fab")
			(effects
				(font
					(size 1.27 1.27)
				)
			)
		)
		(duplicate_pad_numbers_are_jumpers no)
		(fp_rect
			(start 0.3048 0.9906)
			(end -0.3048 -0.1016)
			(stroke
				(width 0)
				(type default)
			)
			(fill no)
			(layer "F.CrtYd")
		)
		(fp_line
			(start 0.3048 -0.1016)
			(end -0.3048 -0.1016)
			(stroke
				(width 0.1)
				(type default)
			)
			(layer "F.Fab")
		)
		(fp_line
			(start -0.3048 -0.1016)
			(end -0.3048 0.9906)
			(stroke
				(width 0.1)
				(type default)
			)
			(layer "F.Fab")
		)
		(fp_line
			(start 0.3048 0.9906)
			(end 0.3048 -0.1016)
			(stroke
				(width 0.1)
				(type default)
			)
			(layer "F.Fab")
		)
		(fp_line
			(start -0.3048 0.9906)
			(end 0.3048 0.9906)
			(stroke
				(width 0.1)
				(type default)
			)
			(layer "F.Fab")
		)
		(pad "1" smd rect
			(at 0 0 90)
			(size 0.508 0.508)
			(layers "F.Cu" "F.Mask" "F.Paste")
			(net "P12V")
		)
		(pad "2" smd rect
			(at 0 0.889 90)
			(size 0.508 0.508)
			(layers "F.Cu" "F.Mask" "F.Paste")
			(net "GND")
		)
		(zone
			(layer "F.Cu")
			(hatch none 0.5)
			(connect_pads
				(clearance 0)
			)
			(min_thickness 0.25)
			(keepout
				(tracks allowed)
				(vias not_allowed)
				(pads allowed)
				(copperpour not_allowed)
				(footprints allowed)
			)
			(placement
				(enabled no)
				(sheetname "")
			)
			(fill
				(thermal_gap 0.5)
				(thermal_bridge_width 0.5)
				(island_removal_mode 0)
			)
			(polygon
				(pts
					(xy 497.755926 -20.957286) (xy 497.374926 -20.957286) (xy 497.374926 -20.449286) (xy 497.755926 -20.449286)
				)
			)
		)
		(zone
			(layer "F.Cu")
			(hatch none 0.5)
			(connect_pads
				(clearance 0)
			)
			(min_thickness 0.25)
			(keepout
				(tracks not_allowed)
				(vias allowed)
				(pads allowed)
				(copperpour not_allowed)
				(footprints allowed)
			)
			(placement
				(enabled no)
				(sheetname "")
			)
			(fill
				(thermal_gap 0.5)
				(thermal_bridge_width 0.5)
				(island_removal_mode 0)
			)
			(polygon
				(pts
					(xy 497.755926 -20.957286) (xy 497.374926 -20.957286) (xy 497.374926 -20.449286) (xy 497.755926 -20.449286)
				)
			)
		)
	)
	(footprint ""
		(layer "F.Cu")
		(at 181.8132 -57.785 -90)
		(property "Reference" "CT63"
			(at -1.19253 2.8956 0)
			(unlocked yes)
			(layer "F.SilkS")
			(effects
				(font
					(size 0.7874 0.5842)
					(thickness 0.1524)
				)
				(justify left)
			)
		)
		(property "Value" ""
			(at 0 0 270)
			(layer "F.Fab")
			(effects
				(font
					(size 1.27 1.27)
				)
			)
		)
		(duplicate_pad_numbers_are_jumpers no)
		(fp_poly
			(pts
				(xy 0.3048 -0.1016) (xy 0.3048 0.9906) (xy -0.3048 0.9906) (xy -0.3048 -0.1016)
			)
			(stroke
				(width 0)
				(type default)
			)
			(fill no)
			(layer "F.CrtYd")
		)
		(fp_line
			(start -0.3048 0.9906)
			(end 0.3048 0.9906)
			(stroke
				(width 0.1)
				(type default)
			)
			(layer "F.Fab")
		)
		(fp_line
			(start 0.3048 0.9906)
			(end 0.3048 -0.1016)
			(stroke
				(width 0.1)
				(type default)
			)
			(layer "F.Fab")
		)
		(fp_line
			(start -0.3048 -0.1016)
			(end -0.3048 0.9906)
			(stroke
				(width 0.1)
				(type default)
			)
			(layer "F.Fab")
		)
		(fp_line
			(start 0.3048 -0.1016)
			(end -0.3048 -0.1016)
			(stroke
				(width 0.1)
				(type default)
			)
			(layer "F.Fab")
		)
		(pad "1" smd rect
			(at 0 0 270)
			(size 0.508 0.508)
			(layers "F.Cu" "F.Mask" "F.Paste")
			(net "VR_PVCCIO_CPU1_AIREF1")
		)
		(pad "2" smd rect
			(at 0 0.889 270)
			(size 0.508 0.508)
			(layers "F.Cu" "F.Mask" "F.Paste")
			(net "GND")
		)
		(zone
			(layer "F.Cu")
			(hatch none 0.5)
			(connect_pads
				(clearance 0)
			)
			(min_thickness 0.25)
			(keepout
				(tracks not_allowed)
				(vias allowed)
				(pads allowed)
				(copperpour not_allowed)
				(footprints allowed)
			)
			(placement
				(enabled no)
				(sheetname "")
			)
			(fill
				(thermal_gap 0.5)
				(thermal_bridge_width 0.5)
				(island_removal_mode 0)
			)
			(polygon
				(pts
					(xy 181.1782 -58.039) (xy 181.1782 -57.531) (xy 181.5592 -57.531) (xy 181.5592 -58.039)
				)
			)
		)
		(zone
			(layer "F.Cu")
			(hatch none 0.5)
			(connect_pads
				(clearance 0)
			)
			(min_thickness 0.25)
			(keepout
				(tracks allowed)
				(vias not_allowed)
				(pads allowed)
				(copperpour not_allowed)
				(footprints allowed)
			)
			(placement
				(enabled no)
				(sheetname "")
			)
			(fill
				(thermal_gap 0.5)
				(thermal_bridge_width 0.5)
				(island_removal_mode 0)
			)
			(polygon
				(pts
					(xy 181.5592 -58.039) (xy 181.5592 -57.531) (xy 181.1782 -57.531) (xy 181.1782 -58.039)
				)
			)
		)
	)
)
